(kicad_pcb
	(version 20260206)
	(generator "pcbnew")
	(generator_version "10.0")
	(general
		(thickness 1.6)
		(legacy_teardrops no)
	)
	(paper "A4")
	(title_block
		(title "03242023_DA0F0TMBIJ0_F0T_Motherboard_J_brd_V01_OCP.brd")
		(comment 1 "Grand Teton / footprints 3511-3515 of 6105")
	)
	(layers
		(0 "F.Cu" signal "TOP")
		(4 "In1.Cu" signal "GND")
		(6 "In2.Cu" signal "IN1")
		(8 "In3.Cu" signal "GND1")
		(10 "In4.Cu" signal "IN2")
		(12 "In5.Cu" signal "GND2")
		(14 "In6.Cu" signal "IN3")
		(16 "In7.Cu" signal "GND3")
		(18 "In8.Cu" signal "VCC")
		(20 "In9.Cu" signal "VCC1")
		(22 "In10.Cu" signal "GND4")
		(24 "In11.Cu" signal "IN4")
		(26 "In12.Cu" signal "GND5")
		(28 "In13.Cu" signal "IN5")
		(30 "In14.Cu" signal "GND6")
		(32 "In15.Cu" signal "IN6")
		(34 "In16.Cu" signal "GND7")
		(2 "B.Cu" signal "BOTTOM")
		(9 "F.Adhes" user "F.Adhesive")
		(11 "B.Adhes" user "B.Adhesive")
		(13 "F.Paste" user "Package Geometry/Pastemask Top")
		(15 "B.Paste" user "Package Geometry/Pastemask Bottom")
		(5 "F.SilkS" user "Ref Des/Silkscreen Top")
		(7 "B.SilkS" user "Ref Des/Silkscreen Bottom")
		(1 "F.Mask" user "Board Geometry/Soldermask Top")
		(3 "B.Mask" user "Board Geometry/Soldermask Bottom")
		(17 "Dwgs.User" user "User.Drawings")
		(19 "Cmts.User" user "User.Comments")
		(21 "Eco1.User" user "User.Eco1")
		(23 "Eco2.User" user "User.Eco2")
		(25 "Edge.Cuts" user "Board Geometry/Outline")
		(27 "Margin" user)
		(31 "F.CrtYd" user "Package Geometry/Place Bound Top")
		(29 "B.CrtYd" user "Package Geometry/Place Bound Bottom")
		(35 "F.Fab" user "Ref Des/Assembly Top")
		(33 "B.Fab" user "Ref Des/Assembly Bottom")
	)
	(footprint ""
		(layer "F.Cu")
		(at 369.461796 -324.445376)
		(property "Reference" "PL11"
			(at 8.906764 3.735578 0)
			(unlocked yes)
			(layer "F.SilkS")
			(effects
				(font
					(size 0.7874 0.5842)
					(thickness 0.1524)
				)
				(justify left)
			)
		)
		(property "Value" ""
			(at 0 0 0)
			(layer "F.Fab")
			(effects
				(font
					(size 1.27 1.27)
				)
			)
		)
		(duplicate_pad_numbers_are_jumpers no)
		(fp_line
			(start -3.750056 -5.500116)
			(end -2.393442 -5.500116)
			(stroke
				(width 0.1524)
				(type default)
			)
			(layer "F.SilkS")
		)
		(fp_line
			(start -3.750056 5.500116)
			(end -3.750056 -5.500116)
			(stroke
				(width 0.1524)
				(type default)
			)
			(layer "F.SilkS")
		)
		(fp_line
			(start -2.393442 5.500116)
			(end -3.750056 5.500116)
			(stroke
				(width 0.1524)
				(type default)
			)
			(layer "F.SilkS")
		)
		(fp_line
			(start 2.393442 5.500116)
			(end 3.750056 5.500116)
			(stroke
				(width 0.1524)
				(type default)
			)
			(layer "F.SilkS")
		)
		(fp_line
			(start 3.750056 -5.500116)
			(end 2.393442 -5.500116)
			(stroke
				(width 0.1524)
				(type default)
			)
			(layer "F.SilkS")
		)
		(fp_line
			(start 3.750056 5.500116)
			(end 3.750056 -5.500116)
			(stroke
				(width 0.1524)
				(type default)
			)
			(layer "F.SilkS")
		)
		(fp_poly
			(pts
				(xy -3.302762 -6.909816) (xy -2.943352 -5.832094) (xy -4.021074 -6.191504)
			)
			(stroke
				(width 0)
				(type default)
			)
			(fill yes)
			(layer "F.SilkS")
		)
		(fp_line
			(start -3.750056 -5.500116)
			(end -3.750056 5.500116)
			(stroke
				(width 0.1)
				(type default)
			)
			(layer "F.Fab")
		)
		(fp_line
			(start -3.750056 5.500116)
			(end 3.750056 5.500116)
			(stroke
				(width 0.1)
				(type default)
			)
			(layer "F.Fab")
		)
		(fp_line
			(start 3.750056 -5.500116)
			(end -3.750056 -5.500116)
			(stroke
				(width 0.1)
				(type default)
			)
			(layer "F.Fab")
		)
		(fp_line
			(start 3.750056 5.500116)
			(end 3.750056 -5.500116)
			(stroke
				(width 0.1)
				(type default)
			)
			(layer "F.Fab")
		)
		(fp_poly
			(pts
				(xy -4.9276 -4.757928) (xy -4.9276 -3.741928) (xy -3.9116 -4.249928)
			)
			(stroke
				(width 0)
				(type default)
			)
			(fill yes)
			(layer "F.Fab")
		)
		(pad "1" smd rect
			(at 0 -4.249928 270)
			(size 2.413 4.5212)
			(layers "F.Cu" "F.Mask" "F.Paste")
			(net "SW_PVCCIN_CPU0_SW4")
		)
		(pad "2" smd rect
			(at 0 -1.175004 270)
			(size 1.3716 4.5212)
			(layers "F.Cu" "F.Mask" "F.Paste")
			(net "IND_P0_CPL4")
		)
		(pad "3" smd rect
			(at 0 1.175004 270)
			(size 1.3716 4.5212)
			(layers "F.Cu" "F.Mask" "F.Paste")
			(net "IND_P0_CPL5")
		)
		(pad "4" smd rect
			(at 0 4.249928 270)
			(size 2.413 4.5212)
			(layers "F.Cu" "F.Mask" "F.Paste")
			(net "PVCCIN_CPU0")
		)
	)
	(footprint ""
		(layer "F.Cu")
		(at 116.561616 -249.320558 -90)
		(property "Reference" "C309"
			(at 0 0 270)
			(layer "F.SilkS")
			(hide yes)
			(effects
				(font
					(size 1.27 1.27)
				)
			)
		)
		(property "Value" ""
			(at 0 0 270)
			(layer "F.Fab")
			(effects
				(font
					(size 1.27 1.27)
				)
			)
		)
		(duplicate_pad_numbers_are_jumpers no)
		(fp_line
			(start -0.7874 0.4064)
			(end -0.7874 -0.4064)
			(stroke
				(width 0.1524)
				(type default)
			)
			(layer "F.SilkS")
		)
		(fp_line
			(start 0.7874 0.4064)
			(end -0.7874 0.4064)
			(stroke
				(width 0.1524)
				(type default)
			)
			(layer "F.SilkS")
		)
		(fp_line
			(start -0.7874 -0.4064)
			(end 0.7874 -0.4064)
			(stroke
				(width 0.1524)
				(type default)
			)
			(layer "F.SilkS")
		)
		(fp_line
			(start 0.7874 -0.4064)
			(end 0.7874 0.4064)
			(stroke
				(width 0.1524)
				(type default)
			)
			(layer "F.SilkS")
		)
		(fp_line
			(start -0.67945 0.3048)
			(end -0.67945 -0.305054)
			(stroke
				(width 0.1)
				(type default)
			)
			(layer "F.Fab")
		)
		(fp_line
			(start -0.12065 0.3048)
			(end -0.67945 0.3048)
			(stroke
				(width 0.1)
				(type default)
			)
			(layer "F.Fab")
		)
		(fp_line
			(start 0.120396 0.3048)
			(end 0.120396 0.2794)
			(stroke
				(width 0.1)
				(type default)
			)
			(layer "F.Fab")
		)
		(fp_line
			(start 0.67945 0.3048)
			(end 0.120396 0.3048)
			(stroke
				(width 0.1)
				(type default)
			)
			(layer "F.Fab")
		)
		(fp_line
			(start -0.12065 0.2794)
			(end -0.12065 0.3048)
			(stroke
				(width 0.1)
				(type default)
			)
			(layer "F.Fab")
		)
		(fp_line
			(start 0.120396 0.2794)
			(end -0.12065 0.2794)
			(stroke
				(width 0.1)
				(type default)
			)
			(layer "F.Fab")
		)
		(fp_line
			(start -0.12065 -0.2794)
			(end 0.12065 -0.2794)
			(stroke
				(width 0.1)
				(type default)
			)
			(layer "F.Fab")
		)
		(fp_line
			(start 0.12065 -0.2794)
			(end 0.12065 -0.3048)
			(stroke
				(width 0.1)
				(type default)
			)
			(layer "F.Fab")
		)
		(fp_line
			(start 0.12065 -0.3048)
			(end 0.67945 -0.3048)
			(stroke
				(width 0.1)
				(type default)
			)
			(layer "F.Fab")
		)
		(fp_line
			(start 0.67945 -0.3048)
			(end 0.67945 0.3048)
			(stroke
				(width 0.1)
				(type default)
			)
			(layer "F.Fab")
		)
		(fp_line
			(start -0.67945 -0.305054)
			(end -0.12065 -0.305054)
			(stroke
				(width 0.1)
				(type default)
			)
			(layer "F.Fab")
		)
		(fp_line
			(start -0.12065 -0.305054)
			(end -0.12065 -0.2794)
			(stroke
				(width 0.1)
				(type default)
			)
			(layer "F.Fab")
		)
		(pad "1" smd circle
			(at -0.40005 0 270)
			(size 0 0)
			(layers "F.Cu" "F.Mask" "F.Paste")
			(net "PVCCIN_CPU1")
		)
		(pad "2" smd circle
			(at 0.40005 0 270)
			(size 0 0)
			(layers "F.Cu" "F.Mask" "F.Paste")
			(net "GND")
		)
	)
	(footprint ""
		(layer "F.Cu")
		(at 258.12496 -360.76382)
		(property "Reference" "H113"
			(at -6.92404 -7.717028 0)
			(unlocked yes)
			(layer "F.SilkS")
			(effects
				(font
					(size 0.7874 0.5842)
					(thickness 0.1524)
				)
				(justify left)
			)
		)
		(property "Value" ""
			(at 0 0 0)
			(layer "F.Fab")
			(effects
				(font
					(size 1.27 1.27)
				)
			)
		)
		(duplicate_pad_numbers_are_jumpers no)
		(fp_circle
			(center 0 0)
			(end 7.999984 0)
			(stroke
				(width 0.1524)
				(type default)
			)
			(fill no)
			(layer "F.SilkS")
		)
		(fp_circle
			(center 0 0)
			(end 7.999984 0)
			(stroke
				(width 0.1524)
				(type default)
			)
			(fill no)
			(layer "B.SilkS")
		)
		(fp_circle
			(center 0 0)
			(end 7.999984 0)
			(stroke
				(width 0.1)
				(type default)
			)
			(fill no)
			(layer "B.Fab")
		)
		(fp_circle
			(center 0 0)
			(end 7.999984 0)
			(stroke
				(width 0.1)
				(type default)
			)
			(fill no)
			(layer "F.Fab")
		)
		(pad "" np_thru_hole circle
			(at 0 0)
			(size 4.0132 4.0132)
			(drill 4.0132)
			(layers "*.Cu" "*.Mask")
			(clearance 0.381)
			(thermal_gap 0.381)
		)
		(pad "2" thru_hole circle
			(at 3.2639 0)
			(size 0.9144 0.9144)
			(drill 0.5588)
			(layers "*.Cu" "*.Mask")
			(remove_unused_layers no)
			(net "GND")
			(clearance 0.0762)
			(thermal_gap 0.0762)
		)
		(pad "3" thru_hole circle
			(at 2.307844 -2.307844)
			(size 0.9144 0.9144)
			(drill 0.5588)
			(layers "*.Cu" "*.Mask")
			(remove_unused_layers no)
			(net "GND")
			(clearance 0.0762)
			(thermal_gap 0.0762)
		)
		(pad "4" thru_hole circle
			(at 0 -3.2639)
			(size 0.9144 0.9144)
			(drill 0.5588)
			(layers "*.Cu" "*.Mask")
			(remove_unused_layers no)
			(net "GND")
			(clearance 0.0762)
			(thermal_gap 0.0762)
		)
		(pad "5" thru_hole circle
			(at -2.307844 -2.307844)
			(size 0.9144 0.9144)
			(drill 0.5588)
			(layers "*.Cu" "*.Mask")
			(remove_unused_layers no)
			(net "GND")
			(clearance 0.0762)
			(thermal_gap 0.0762)
		)
		(pad "6" thru_hole circle
			(at -3.2639 0)
			(size 0.9144 0.9144)
			(drill 0.5588)
			(layers "*.Cu" "*.Mask")
			(remove_unused_layers no)
			(net "GND")
			(clearance 0.0762)
			(thermal_gap 0.0762)
		)
		(pad "7" thru_hole circle
			(at -2.307844 2.307844)
			(size 0.9144 0.9144)
			(drill 0.5588)
			(layers "*.Cu" "*.Mask")
			(remove_unused_layers no)
			(net "GND")
			(clearance 0.0762)
			(thermal_gap 0.0762)
		)
		(pad "8" thru_hole circle
			(at 0 3.2639)
			(size 0.9144 0.9144)
			(drill 0.5588)
			(layers "*.Cu" "*.Mask")
			(remove_unused_layers no)
			(net "GND")
			(clearance 0.0762)
			(thermal_gap 0.0762)
		)
		(pad "9" thru_hole circle
			(at 2.307844 2.307844)
			(size 0.9144 0.9144)
			(drill 0.5588)
			(layers "*.Cu" "*.Mask")
			(remove_unused_layers no)
			(net "GND")
			(clearance 0.0762)
			(thermal_gap 0.0762)
		)
		(zone
			(layer "F.Cu")
			(hatch none 0.5)
			(connect_pads
				(clearance 0)
			)
			(min_thickness 0.25)
			(keepout
				(tracks not_allowed)
				(vias allowed)
				(pads allowed)
				(copperpour not_allowed)
				(footprints allowed)
			)
			(placement
				(enabled no)
				(sheetname "")
			)
			(fill
				(thermal_gap 0.5)
				(thermal_bridge_width 0.5)
				(island_removal_mode 0)
			)
			(polygon
				(pts
					(arc
						(start 258.12496 -356.49662)
						(mid 253.85776 -360.76382)
						(end 258.12496 -365.03102)
					)
					(arc
						(start 258.12496 -368.763804)
						(mid 252.468117 -366.420663)
						(end 250.124976 -360.76382)
					)
					(arc
						(start 250.124976 -360.76382)
						(mid 252.468117 -355.106977)
						(end 258.12496 -352.763836)
					)
				)
			)
		)
		(zone
			(layer "F.Cu")
			(hatch none 0.5)
			(connect_pads
				(clearance 0)
			)
			(min_thickness 0.25)
			(keepout
				(tracks not_allowed)
				(vias allowed)
				(pads allowed)
				(copperpour not_allowed)
				(footprints allowed)
			)
			(placement
				(enabled no)
				(sheetname "")
			)
			(fill
				(thermal_gap 0.5)
				(thermal_bridge_width 0.5)
				(island_removal_mode 0)
			)
			(polygon
				(pts
					(arc
						(start 258.12496 -356.49662)
						(mid 262.39216 -360.76382)
						(end 258.12496 -365.03102)
					)
					(arc
						(start 258.12496 -368.763804)
						(mid 263.781803 -366.420663)
						(end 266.124944 -360.76382)
					)
					(arc
						(start 266.124944 -360.76382)
						(mid 263.781803 -355.106977)
						(end 258.12496 -352.763836)
					)
				)
			)
		)
		(zone
			(layers "F.Cu" "B.Cu" "In1.Cu" "In2.Cu" "In3.Cu" "In4.Cu" "In5.Cu" "In6.Cu"
				"In7.Cu" "In8.Cu" "In9.Cu" "In10.Cu" "In11.Cu" "In12.Cu" "In13.Cu" "In14.Cu"
				"In15.Cu" "In16.Cu"
			)
			(hatch none 0.5)
			(connect_pads
				(clearance 0)
			)
			(min_thickness 0.25)
			(keepout
				(tracks not_allowed)
				(vias allowed)
				(pads allowed)
				(copperpour not_allowed)
				(footprints allowed)
			)
			(placement
				(enabled no)
				(sheetname "")
			)
			(fill
				(thermal_gap 0.5)
				(thermal_bridge_width 0.5)
				(island_removal_mode 0)
			)
			(polygon
				(pts
					(arc
						(start 260.63702 -360.76382)
						(mid 255.6129 -360.76382)
						(end 260.63702 -360.76382)
					)
				)
			)
		)
		(zone
			(layer "B.Cu")
			(hatch none 0.5)
			(connect_pads
				(clearance 0)
			)
			(min_thickness 0.25)
			(keepout
				(tracks not_allowed)
				(vias allowed)
				(pads allowed)
				(copperpour not_allowed)
				(footprints allowed)
			)
			(placement
				(enabled no)
				(sheetname "")
			)
			(fill
				(thermal_gap 0.5)
				(thermal_bridge_width 0.5)
				(island_removal_mode 0)
			)
			(polygon
				(pts
					(arc
						(start 258.12496 -365.28502)
						(mid 253.60376 -360.76382)
						(end 258.12496 -356.24262)
					)
					(arc
						(start 258.12496 -356.72522)
						(mid 254.08636 -360.76382)
						(end 258.12496 -364.80242)
					)
				)
			)
		)
		(zone
			(layer "B.Cu")
			(hatch none 0.5)
			(connect_pads
				(clearance 0)
			)
			(min_thickness 0.25)
			(keepout
				(tracks not_allowed)
				(vias allowed)
				(pads allowed)
				(copperpour not_allowed)
				(footprints allowed)
			)
			(placement
				(enabled no)
				(sheetname "")
			)
			(fill
				(thermal_gap 0.5)
				(thermal_bridge_width 0.5)
				(island_removal_mode 0)
			)
			(polygon
				(pts
					(arc
						(start 258.12496 -365.28502)
						(mid 262.64616 -360.76382)
						(end 258.12496 -356.24262)
					)
					(arc
						(start 258.12496 -356.72522)
						(mid 262.16356 -360.76382)
						(end 258.12496 -364.80242)
					)
				)
			)
		)
	)
	(footprint ""
		(layer "F.Cu")
		(at 182.82158 -417.7157)
		(property "Reference" "C2390"
			(at 0 0 0)
			(layer "F.SilkS")
			(hide yes)
			(effects
				(font
					(size 1.27 1.27)
				)
			)
		)
		(property "Value" ""
			(at 0 0 0)
			(layer "F.Fab")
			(effects
				(font
					(size 1.27 1.27)
				)
			)
		)
		(duplicate_pad_numbers_are_jumpers no)
		(fp_line
			(start -0.7874 -0.4064)
			(end 0.7874 -0.4064)
			(stroke
				(width 0.1524)
				(type default)
			)
			(layer "F.SilkS")
		)
		(fp_line
			(start -0.7874 0.4064)
			(end -0.7874 -0.4064)
			(stroke
				(width 0.1524)
				(type default)
			)
			(layer "F.SilkS")
		)
		(fp_line
			(start 0.7874 -0.4064)
			(end 0.7874 0.4064)
			(stroke
				(width 0.1524)
				(type default)
			)
			(layer "F.SilkS")
		)
		(fp_line
			(start 0.7874 0.4064)
			(end -0.7874 0.4064)
			(stroke
				(width 0.1524)
				(type default)
			)
			(layer "F.SilkS")
		)
		(fp_line
			(start -0.67945 -0.305054)
			(end -0.12065 -0.305054)
			(stroke
				(width 0.1)
				(type default)
			)
			(layer "F.Fab")
		)
		(fp_line
			(start -0.67945 0.3048)
			(end -0.67945 -0.305054)
			(stroke
				(width 0.1)
				(type default)
			)
			(layer "F.Fab")
		)
		(fp_line
			(start -0.12065 -0.305054)
			(end -0.12065 -0.2794)
			(stroke
				(width 0.1)
				(type default)
			)
			(layer "F.Fab")
		)
		(fp_line
			(start -0.12065 -0.2794)
			(end 0.12065 -0.2794)
			(stroke
				(width 0.1)
				(type default)
			)
			(layer "F.Fab")
		)
		(fp_line
			(start -0.12065 0.2794)
			(end -0.12065 0.3048)
			(stroke
				(width 0.1)
				(type default)
			)
			(layer "F.Fab")
		)
		(fp_line
			(start -0.12065 0.3048)
			(end -0.67945 0.3048)
			(stroke
				(width 0.1)
				(type default)
			)
			(layer "F.Fab")
		)
		(fp_line
			(start 0.120396 0.2794)
			(end -0.12065 0.2794)
			(stroke
				(width 0.1)
				(type default)
			)
			(layer "F.Fab")
		)
		(fp_line
			(start 0.120396 0.3048)
			(end 0.120396 0.2794)
			(stroke
				(width 0.1)
				(type default)
			)
			(layer "F.Fab")
		)
		(fp_line
			(start 0.12065 -0.3048)
			(end 0.67945 -0.3048)
			(stroke
				(width 0.1)
				(type default)
			)
			(layer "F.Fab")
		)
		(fp_line
			(start 0.12065 -0.2794)
			(end 0.12065 -0.3048)
			(stroke
				(width 0.1)
				(type default)
			)
			(layer "F.Fab")
		)
		(fp_line
			(start 0.67945 -0.3048)
			(end 0.67945 0.3048)
			(stroke
				(width 0.1)
				(type default)
			)
			(layer "F.Fab")
		)
		(fp_line
			(start 0.67945 0.3048)
			(end 0.120396 0.3048)
			(stroke
				(width 0.1)
				(type default)
			)
			(layer "F.Fab")
		)
		(pad "1" smd circle
			(at -0.40005 0)
			(size 0 0)
			(layers "F.Cu" "F.Mask" "F.Paste")
			(net "P12V_AUX")
		)
		(pad "2" smd circle
			(at 0.40005 0)
			(size 0 0)
			(layers "F.Cu" "F.Mask" "F.Paste")
			(net "GND")
		)
	)
	(footprint ""
		(layer "F.Cu")
		(at 117.22608 -122.132598 90)
		(property "Reference" "R938"
			(at 0 0 90)
			(layer "F.SilkS")
			(hide yes)
			(effects
				(font
					(size 1.27 1.27)
				)
			)
		)
		(property "Value" ""
			(at 0 0 90)
			(layer "F.Fab")
			(effects
				(font
					(size 1.27 1.27)
				)
			)
		)
		(duplicate_pad_numbers_are_jumpers no)
		(fp_line
			(start 0.7874 -0.4064)
			(end 0.7874 0.4064)
			(stroke
				(width 0.1524)
				(type default)
			)
			(layer "F.SilkS")
		)
		(fp_line
			(start -0.7874 -0.4064)
			(end 0.7874 -0.4064)
			(stroke
				(width 0.1524)
				(type default)
			)
			(layer "F.SilkS")
		)
		(fp_line
			(start 0.7874 0.4064)
			(end -0.7874 0.4064)
			(stroke
				(width 0.1524)
				(type default)
			)
			(layer "F.SilkS")
		)
		(fp_line
			(start -0.7874 0.4064)
			(end -0.7874 -0.4064)
			(stroke
				(width 0.1524)
				(type default)
			)
			(layer "F.SilkS")
		)
		(fp_line
			(start -0.12065 -0.305054)
			(end -0.12065 -0.2794)
			(stroke
				(width 0.1)
				(type default)
			)
			(layer "F.Fab")
		)
		(fp_line
			(start -0.67945 -0.305054)
			(end -0.12065 -0.305054)
			(stroke
				(width 0.1)
				(type default)
			)
			(layer "F.Fab")
		)
		(fp_line
			(start 0.67945 -0.3048)
			(end 0.67945 0.3048)
			(stroke
				(width 0.1)
				(type default)
			)
			(layer "F.Fab")
		)
		(fp_line
			(start 0.12065 -0.3048)
			(end 0.67945 -0.3048)
			(stroke
				(width 0.1)
				(type default)
			)
			(layer "F.Fab")
		)
		(fp_line
			(start 0.12065 -0.2794)
			(end 0.12065 -0.3048)
			(stroke
				(width 0.1)
				(type default)
			)
			(layer "F.Fab")
		)
		(fp_line
			(start -0.12065 -0.2794)
			(end 0.12065 -0.2794)
			(stroke
				(width 0.1)
				(type default)
			)
			(layer "F.Fab")
		)
		(fp_line
			(start 0.120396 0.2794)
			(end -0.12065 0.2794)
			(stroke
				(width 0.1)
				(type default)
			)
			(layer "F.Fab")
		)
		(fp_line
			(start -0.12065 0.2794)
			(end -0.12065 0.3048)
			(stroke
				(width 0.1)
				(type default)
			)
			(layer "F.Fab")
		)
		(fp_line
			(start 0.67945 0.3048)
			(end 0.120396 0.3048)
			(stroke
				(width 0.1)
				(type default)
			)
			(layer "F.Fab")
		)
		(fp_line
			(start 0.120396 0.3048)
			(end 0.120396 0.2794)
			(stroke
				(width 0.1)
				(type default)
			)
			(layer "F.Fab")
		)
		(fp_line
			(start -0.12065 0.3048)
			(end -0.67945 0.3048)
			(stroke
				(width 0.1)
				(type default)
			)
			(layer "F.Fab")
		)
		(fp_line
			(start -0.67945 0.3048)
			(end -0.67945 -0.305054)
			(stroke
				(width 0.1)
				(type default)
			)
			(layer "F.Fab")
		)
		(pad "1" smd circle
			(at -0.40005 0 90)
			(size 0 0)
			(layers "F.Cu" "F.Mask" "F.Paste")
			(net "RST_CPU0_DRAM_GH_N")
		)
		(pad "2" smd circle
			(at 0.40005 0 90)
			(size 0 0)
			(layers "F.Cu" "F.Mask" "F.Paste")
			(net "GND")
		)
	)
)
